# T6G (Grand Teton) — schematic netlist excerpt (pin names and nets, part order shuffled) for the footprints in the layout excerpt that follows; sources: Cadence DE-HDL packaged netlist, KiCad conversion of 04192023_DAF0TMB3IC0_F0TG_MB_C_brd_V02_OCP.brd

R1710  Q_RES  10 1% CHIP  pkg 0402LF  page 108 : A = I3C_SPD_DDRGL_CPU1_SDA ; B = I3C_SPD_DDRK_CPU1_SDA
C6620  Q_CAP_DIFFBUS  DIFF BUS_0.22UF 6.3V 20% X6S  pkg C0201  page 308 : \1\ = P5E_CPU0_P3_TX_BUF_C_DN<11> ; \2\ = P5E_CPU0_P3_TX_BUF_DN<11>
PC96_2  Q_CAP  22UF 16V 20% X6S  pkg C0805  page 201 : A = SW_P12V_AUX_PVDDCR_CPU1_P0_FLT ; B = GND

(kicad_pcb
	(version 20260206)
	(generator "pcbnew")
	(generator_version "10.0")
	(general
		(thickness 1.6)
		(legacy_teardrops no)
	)
	(paper "A4")
	(title_block
		(title "04192023_DAF0TMB3IC0_F0TG_MB_C_brd_V02_OCP.brd")
		(comment 1 "Grand Teton / footprints 6130-6132 of 8354")
	)
	(layers
		(0 "F.Cu" signal "TOP")
		(4 "In1.Cu" signal "GND")
		(6 "In2.Cu" signal "IN1")
		(8 "In3.Cu" signal "GND1")
		(10 "In4.Cu" signal "IN2")
		(12 "In5.Cu" signal "GND2")
		(14 "In6.Cu" signal "IN3")
		(16 "In7.Cu" signal "GND3")
		(18 "In8.Cu" signal "VCC")
		(20 "In9.Cu" signal "VCC1")
		(22 "In10.Cu" signal "GND4")
		(24 "In11.Cu" signal "IN4")
		(26 "In12.Cu" signal "GND5")
		(28 "In13.Cu" signal "IN5")
		(30 "In14.Cu" signal "GND6")
		(32 "In15.Cu" signal "IN6")
		(34 "In16.Cu" signal "GND7")
		(2 "B.Cu" signal "BOTTOM")
		(9 "F.Adhes" user "F.Adhesive")
		(11 "B.Adhes" user "B.Adhesive")
		(13 "F.Paste" user "Package Geometry/Pastemask Top")
		(15 "B.Paste" user "Package Geometry/Pastemask Bottom")
		(5 "F.SilkS" user "Ref Des/Silkscreen Top")
		(7 "B.SilkS" user "Ref Des/Silkscreen Bottom")
		(1 "F.Mask" user "Board Geometry/Soldermask Top")
		(3 "B.Mask" user "Board Geometry/Soldermask Bottom")
		(17 "Dwgs.User" user "User.Drawings")
		(19 "Cmts.User" user "User.Comments")
		(21 "Eco1.User" user "User.Eco1")
		(23 "Eco2.User" user "User.Eco2")
		(25 "Edge.Cuts" user "Board Geometry/Outline")
		(27 "Margin" user)
		(31 "F.CrtYd" user "Package Geometry/Place Bound Top")
		(29 "B.CrtYd" user "Package Geometry/Place Bound Bottom")
		(35 "F.Fab" user "Ref Des/Assembly Top")
		(33 "B.Fab" user "Ref Des/Assembly Bottom")
	)
	(footprint ""
		(layer "B.Cu")
		(at 197.94855 -195.8594 180)
		(property "Reference" "R1710"
			(at 0 0 0)
			(layer "B.SilkS")
			(hide yes)
			(effects
				(font
					(size 1.27 1.27)
				)
				(justify mirror)
			)
		)
		(property "Value" ""
			(at 0 0 0)
			(layer "B.Fab")
			(effects
				(font
					(size 1.27 1.27)
				)
				(justify mirror)
			)
		)
		(duplicate_pad_numbers_are_jumpers no)
		(fp_line
			(start 0.7874 0.4064)
			(end 0.7874 -0.4064)
			(stroke
				(width 0.1524)
				(type default)
			)
			(layer "B.SilkS")
		)
		(fp_line
			(start 0.7874 -0.4064)
			(end -0.7874 -0.4064)
			(stroke
				(width 0.1524)
				(type default)
			)
			(layer "B.SilkS")
		)
		(fp_line
			(start -0.7874 0.4064)
			(end 0.7874 0.4064)
			(stroke
				(width 0.1524)
				(type default)
			)
			(layer "B.SilkS")
		)
		(fp_line
			(start -0.7874 -0.4064)
			(end -0.7874 0.4064)
			(stroke
				(width 0.1524)
				(type default)
			)
			(layer "B.SilkS")
		)
		(fp_line
			(start 0.67945 0.3048)
			(end 0.67945 -0.305054)
			(stroke
				(width 0.1)
				(type default)
			)
			(layer "B.Fab")
		)
		(fp_line
			(start 0.67945 -0.305054)
			(end 0.12065 -0.305054)
			(stroke
				(width 0.1)
				(type default)
			)
			(layer "B.Fab")
		)
		(fp_line
			(start 0.12065 0.3048)
			(end 0.67945 0.3048)
			(stroke
				(width 0.1)
				(type default)
			)
			(layer "B.Fab")
		)
		(fp_line
			(start 0.12065 0.2794)
			(end 0.12065 0.3048)
			(stroke
				(width 0.1)
				(type default)
			)
			(layer "B.Fab")
		)
		(fp_line
			(start 0.12065 -0.2794)
			(end -0.12065 -0.2794)
			(stroke
				(width 0.1)
				(type default)
			)
			(layer "B.Fab")
		)
		(fp_line
			(start 0.12065 -0.305054)
			(end 0.12065 -0.2794)
			(stroke
				(width 0.1)
				(type default)
			)
			(layer "B.Fab")
		)
		(fp_line
			(start -0.120396 0.3048)
			(end -0.120396 0.2794)
			(stroke
				(width 0.1)
				(type default)
			)
			(layer "B.Fab")
		)
		(fp_line
			(start -0.120396 0.2794)
			(end 0.12065 0.2794)
			(stroke
				(width 0.1)
				(type default)
			)
			(layer "B.Fab")
		)
		(fp_line
			(start -0.12065 -0.2794)
			(end -0.12065 -0.3048)
			(stroke
				(width 0.1)
				(type default)
			)
			(layer "B.Fab")
		)
		(fp_line
			(start -0.12065 -0.3048)
			(end -0.67945 -0.3048)
			(stroke
				(width 0.1)
				(type default)
			)
			(layer "B.Fab")
		)
		(fp_line
			(start -0.67945 0.3048)
			(end -0.120396 0.3048)
			(stroke
				(width 0.1)
				(type default)
			)
			(layer "B.Fab")
		)
		(fp_line
			(start -0.67945 -0.3048)
			(end -0.67945 0.3048)
			(stroke
				(width 0.1)
				(type default)
			)
			(layer "B.Fab")
		)
		(pad "1" smd circle
			(at 0.40005 0)
			(size 0 0)
			(layers "B.Cu" "B.Mask" "B.Paste")
			(net "I3C_SPD_DDRGL_CPU1_SDA")
		)
		(pad "2" smd circle
			(at -0.40005 0)
			(size 0 0)
			(layers "B.Cu" "B.Mask" "B.Paste")
			(net "I3C_SPD_DDRK_CPU1_SDA")
		)
	)
	(footprint ""
		(layer "B.Cu")
		(at 327.823068 -335.055972 90)
		(property "Reference" "PC96_2"
			(at 0 0 90)
			(layer "B.SilkS")
			(hide yes)
			(effects
				(font
					(size 1.27 1.27)
				)
				(justify mirror)
			)
		)
		(property "Value" ""
			(at 0 0 90)
			(layer "B.Fab")
			(effects
				(font
					(size 1.27 1.27)
				)
				(justify mirror)
			)
		)
		(duplicate_pad_numbers_are_jumpers no)
		(fp_line
			(start 1.524 -0.762)
			(end -1.524 -0.762)
			(stroke
				(width 0.1524)
				(type default)
			)
			(layer "B.SilkS")
		)
		(fp_line
			(start -1.524 -0.762)
			(end -1.524 0.762)
			(stroke
				(width 0.1524)
				(type default)
			)
			(layer "B.SilkS")
		)
		(fp_line
			(start 1.524 0.762)
			(end 1.524 -0.762)
			(stroke
				(width 0.1524)
				(type default)
			)
			(layer "B.SilkS")
		)
		(fp_line
			(start -1.524 0.762)
			(end 1.524 0.762)
			(stroke
				(width 0.1524)
				(type default)
			)
			(layer "B.SilkS")
		)
		(fp_line
			(start 1.1049 -0.724916)
			(end 1.1049 0.724916)
			(stroke
				(width 0.1)
				(type default)
			)
			(layer "B.Fab")
		)
		(fp_line
			(start -1.1049 -0.724916)
			(end 1.1049 -0.724916)
			(stroke
				(width 0.1)
				(type default)
			)
			(layer "B.Fab")
		)
		(fp_line
			(start 1.1049 0.724916)
			(end -1.1049 0.724916)
			(stroke
				(width 0.1)
				(type default)
			)
			(layer "B.Fab")
		)
		(fp_line
			(start -1.1049 0.724916)
			(end -1.1049 -0.724916)
			(stroke
				(width 0.1)
				(type default)
			)
			(layer "B.Fab")
		)
		(pad "1" smd rect
			(at 0.889 0 90)
			(size 1.016 1.27)
			(layers "B.Cu" "B.Mask" "B.Paste")
			(net "SW_P12V_AUX_PVDDCR_CPU1_P0_FLT")
		)
		(pad "2" smd rect
			(at -0.889 0 90)
			(size 1.016 1.27)
			(layers "B.Cu" "B.Mask" "B.Paste")
			(net "GND")
		)
	)
	(footprint ""
		(layer "B.Cu")
		(at 406.095962 -416.899344 90)
		(property "Reference" "C6620"
			(at 0 0 90)
			(layer "B.SilkS")
			(hide yes)
			(effects
				(font
					(size 1.27 1.27)
				)
				(justify mirror)
			)
		)
		(property "Value" ""
			(at 0 0 90)
			(layer "B.Fab")
			(effects
				(font
					(size 1.27 1.27)
				)
				(justify mirror)
			)
		)
		(duplicate_pad_numbers_are_jumpers no)
		(fp_line
			(start 0.299974 -0.150114)
			(end -0.299974 -0.150114)
			(stroke
				(width 0.1)
				(type default)
			)
			(layer "B.Fab")
		)
		(fp_line
			(start -0.299974 -0.150114)
			(end -0.299974 0.150114)
			(stroke
				(width 0.1)
				(type default)
			)
			(layer "B.Fab")
		)
		(fp_line
			(start 0.299974 0.150114)
			(end 0.299974 -0.150114)
			(stroke
				(width 0.1)
				(type default)
			)
			(layer "B.Fab")
		)
		(fp_line
			(start -0.299974 0.150114)
			(end 0.299974 0.150114)
			(stroke
				(width 0.1)
				(type default)
			)
			(layer "B.Fab")
		)
		(pad "1" smd rect
			(at 0.2667 0 270)
			(size 0.3048 0.381)
			(layers "B.Cu" "B.Mask" "B.Paste")
			(net "P5E_CPU0_P3_TX_BUF_C_DN<11>")
		)
		(pad "2" smd rect
			(at -0.2667 0 270)
			(size 0.3048 0.381)
			(layers "B.Cu" "B.Mask" "B.Paste")
			(net "P5E_CPU0_P3_TX_BUF_DN<11>")
		)
	)
)
